(kicad_pcb
	(version 20260206)
	(generator "pcbnew")
	(generator_version "10.0")
	(general
		(thickness 1.6)
		(legacy_teardrops no)
	)
	(paper "A4")
	(title_block
		(title "Bryce Canyon_SCC_16316-1_OCP.brd")
		(comment 1 "Bryce Canyon / footprints 742-748 of 1561")
	)
	(layers
		(0 "F.Cu" signal "TOP")
		(4 "In1.Cu" signal "L2GND")
		(6 "In2.Cu" signal "L3")
		(8 "In3.Cu" signal "L4VCC")
		(10 "In4.Cu" signal "L5VCC")
		(12 "In5.Cu" signal "L6")
		(14 "In6.Cu" signal "L7GND")
		(2 "B.Cu" signal "BOTTOM")
		(9 "F.Adhes" user "F.Adhesive")
		(11 "B.Adhes" user "B.Adhesive")
		(13 "F.Paste" user "Package Geometry/Pastemask Top")
		(15 "B.Paste" user "Package Geometry/Pastemask Bottom")
		(5 "F.SilkS" user "Ref Des/Silkscreen Top")
		(7 "B.SilkS" user "Ref Des/Silkscreen Bottom")
		(1 "F.Mask" user "Board Geometry/Soldermask Top")
		(3 "B.Mask" user "Board Geometry/Soldermask Bottom")
		(17 "Dwgs.User" user "User.Drawings")
		(19 "Cmts.User" user "User.Comments")
		(21 "Eco1.User" user "User.Eco1")
		(23 "Eco2.User" user "User.Eco2")
		(25 "Edge.Cuts" user "Board Geometry/Outline")
		(27 "Margin" user)
		(31 "F.CrtYd" user "Package Geometry/Place Bound Top")
		(29 "B.CrtYd" user "Package Geometry/Place Bound Bottom")
		(35 "F.Fab" user "Ref Des/Assembly Top")
		(33 "B.Fab" user "Ref Des/Assembly Bottom")
	)
	(footprint ""
		(layer "F.Cu")
		(at 166.751 -17.018 180)
		(property "Reference" "Q20"
			(at 0 0 180)
			(layer "F.SilkS")
			(hide yes)
			(effects
				(font
					(size 1.27 1.27)
				)
			)
		)
		(property "Value" "2N7002K-1-GP"
			(at 0.127 -8.9662 180)
			(unlocked yes)
			(layer "F.Fab")
			(hide yes)
			(effects
				(font
					(size 1.016 1.016)
					(thickness 0.1524)
				)
			)
		)
		(property "Device Type" "SOT23DGS2D4H44"
			(at 0.127 -10.4902 180)
			(unlocked yes)
			(layer "F.Fab")
			(hide yes)
			(effects
				(font
					(size 1.016 1.016)
					(thickness 0.1524)
				)
			)
		)
		(duplicate_pad_numbers_are_jumpers no)
		(fp_line
			(start 1.651 1.778)
			(end 1.651 -1.778)
			(stroke
				(width 0.1524)
				(type default)
			)
			(layer "F.SilkS")
		)
		(fp_line
			(start 1.651 -1.778)
			(end -1.651 -1.778)
			(stroke
				(width 0.1524)
				(type default)
			)
			(layer "F.SilkS")
		)
		(fp_line
			(start -1.651 1.778)
			(end 1.651 1.778)
			(stroke
				(width 0.1524)
				(type default)
			)
			(layer "F.SilkS")
		)
		(fp_line
			(start -1.651 -1.778)
			(end -1.651 1.778)
			(stroke
				(width 0.1524)
				(type default)
			)
			(layer "F.SilkS")
		)
		(fp_poly
			(pts
				(xy -1.778 1.8796) (xy -1.778 -1.8796) (xy 1.778 -1.8796) (xy 1.778 1.8796)
			)
			(stroke
				(width 0)
				(type default)
			)
			(fill no)
			(layer "F.CrtYd")
		)
		(fp_poly
			(pts
				(xy -1.778 1.8796) (xy -1.778 -1.8796) (xy 1.778 -1.8796) (xy 1.778 1.8796)
			)
			(stroke
				(width 0)
				(type default)
			)
			(fill no)
			(layer "F.Fab")
		)
		(pad "D" smd custom
			(at 0 -0.9525 180)
			(size 0.1905 0.1905)
			(layers "F.Cu" "F.Mask" "F.Paste")
			(net "LS_EN_N")
			(options
				(clearance outline)
				(anchor circle)
			)
			(primitives
				(gr_poly
					(pts
						(arc
							(start -0.1778 0.5715)
							(mid -0.321484 0.511984)
							(end -0.381 0.3683)
						)
						(arc
							(start -0.381 -0.3683)
							(mid -0.321484 -0.511984)
							(end -0.1778 -0.5715)
						)
						(arc
							(start 0.1778 -0.5715)
							(mid 0.321484 -0.511984)
							(end 0.381 -0.3683)
						)
						(arc
							(start 0.381 0.3683)
							(mid 0.321484 0.511984)
							(end 0.1778 0.5715)
						)
					)
					(width 0)
					(fill yes)
				)
			)
		)
		(pad "G" smd custom
			(at -0.98425 0.9525 180)
			(size 0.1905 0.1905)
			(layers "F.Cu" "F.Mask" "F.Paste")
			(net "P0V9_PG_Q")
			(options
				(clearance outline)
				(anchor circle)
			)
			(primitives
				(gr_poly
					(pts
						(arc
							(start -0.1778 0.5715)
							(mid -0.321484 0.511984)
							(end -0.381 0.3683)
						)
						(arc
							(start -0.381 -0.3683)
							(mid -0.321484 -0.511984)
							(end -0.1778 -0.5715)
						)
						(arc
							(start 0.1778 -0.5715)
							(mid 0.321484 -0.511984)
							(end 0.381 -0.3683)
						)
						(arc
							(start 0.381 0.3683)
							(mid 0.321484 0.511984)
							(end 0.1778 0.5715)
						)
					)
					(width 0)
					(fill yes)
				)
			)
		)
		(pad "S" smd custom
			(at 0.98425 0.9525 180)
			(size 0.1905 0.1905)
			(layers "F.Cu" "F.Mask" "F.Paste")
			(net "GND")
			(options
				(clearance outline)
				(anchor circle)
			)
			(primitives
				(gr_poly
					(pts
						(arc
							(start -0.1778 0.5715)
							(mid -0.321484 0.511984)
							(end -0.381 0.3683)
						)
						(arc
							(start -0.381 -0.3683)
							(mid -0.321484 -0.511984)
							(end -0.1778 -0.5715)
						)
						(arc
							(start 0.1778 -0.5715)
							(mid 0.321484 -0.511984)
							(end 0.381 -0.3683)
						)
						(arc
							(start 0.381 0.3683)
							(mid 0.321484 0.511984)
							(end 0.1778 0.5715)
						)
					)
					(width 0)
					(fill yes)
				)
			)
		)
	)
	(footprint ""
		(layer "F.Cu")
		(at 191.850772 -46.520862 -90)
		(property "Reference" "R217"
			(at 0 0 270)
			(layer "F.SilkS")
			(hide yes)
			(effects
				(font
					(size 1.27 1.27)
				)
			)
		)
		(property "Value" "10KR2F-2-GP"
			(at 0.064008 -3.993896 270)
			(unlocked yes)
			(layer "F.Fab")
			(hide yes)
			(effects
				(font
					(size 1.016 1.016)
					(thickness 0.1524)
				)
			)
		)
		(property "Device Type" "R402H16"
			(at 0.064008 -5.517896 270)
			(unlocked yes)
			(layer "F.Fab")
			(hide yes)
			(effects
				(font
					(size 1.016 1.016)
					(thickness 0.1524)
				)
			)
		)
		(duplicate_pad_numbers_are_jumpers no)
		(fp_line
			(start -0.508 -0.9398)
			(end -0.508 0.9398)
			(stroke
				(width 0.1524)
				(type default)
			)
			(layer "F.SilkS")
		)
		(fp_line
			(start 0.508 -0.9398)
			(end -0.508 -0.9398)
			(stroke
				(width 0.1524)
				(type default)
			)
			(layer "F.SilkS")
		)
		(fp_rect
			(start -0.508 0.9398)
			(end 0.508 -0.9398)
			(stroke
				(width 0)
				(type default)
			)
			(fill no)
			(layer "F.CrtYd")
		)
		(fp_rect
			(start -0.508 0.9398)
			(end 0.508 -0.9398)
			(stroke
				(width 0)
				(type default)
			)
			(fill no)
			(layer "F.Fab")
		)
		(pad "1" smd custom
			(at 0 -0.4445 270)
			(size 0.1397 0.1397)
			(layers "F.Cu" "F.Mask" "F.Paste")
			(net "P1V8_C")
			(options
				(clearance outline)
				(anchor circle)
			)
			(primitives
				(gr_poly
					(pts
						(arc
							(start -0.1778 -0.2794)
							(mid -0.249642 -0.249642)
							(end -0.2794 -0.1778)
						)
						(arc
							(start -0.2794 0.1778)
							(mid -0.249642 0.249642)
							(end -0.1778 0.2794)
						)
						(arc
							(start 0.1778 0.2794)
							(mid 0.249642 0.249642)
							(end 0.2794 0.1778)
						)
						(arc
							(start 0.2794 -0.1778)
							(mid 0.249642 -0.249642)
							(end 0.1778 -0.2794)
						)
					)
					(width 0)
					(fill yes)
				)
			)
		)
		(pad "2" smd custom
			(at 0 0.4445 270)
			(size 0.1397 0.1397)
			(layers "F.Cu" "F.Mask" "F.Paste")
			(net "XM_ADDR_23")
			(options
				(clearance outline)
				(anchor circle)
			)
			(primitives
				(gr_poly
					(pts
						(arc
							(start -0.1778 -0.2794)
							(mid -0.249642 -0.249642)
							(end -0.2794 -0.1778)
						)
						(arc
							(start -0.2794 0.1778)
							(mid -0.249642 0.249642)
							(end -0.1778 0.2794)
						)
						(arc
							(start 0.1778 0.2794)
							(mid 0.249642 0.249642)
							(end 0.2794 0.1778)
						)
						(arc
							(start 0.2794 -0.1778)
							(mid 0.249642 -0.249642)
							(end 0.1778 -0.2794)
						)
					)
					(width 0)
					(fill yes)
				)
			)
		)
	)
	(footprint ""
		(layer "F.Cu")
		(at 49.558702 -29.119576 90)
		(property "Reference" "R474"
			(at 0 0 90)
			(layer "F.SilkS")
			(hide yes)
			(effects
				(font
					(size 1.27 1.27)
				)
			)
		)
		(property "Value" "10R2J-2-GP"
			(at 0.064008 -3.993896 90)
			(unlocked yes)
			(layer "F.Fab")
			(hide yes)
			(effects
				(font
					(size 1.016 1.016)
					(thickness 0.1524)
				)
			)
		)
		(property "Device Type" "R402H14"
			(at 0.064008 -5.517896 90)
			(unlocked yes)
			(layer "F.Fab")
			(hide yes)
			(effects
				(font
					(size 1.016 1.016)
					(thickness 0.1524)
				)
			)
		)
		(duplicate_pad_numbers_are_jumpers no)
		(fp_line
			(start 0.508 -0.9398)
			(end -0.508 -0.9398)
			(stroke
				(width 0.1524)
				(type default)
			)
			(layer "F.SilkS")
		)
		(fp_line
			(start -0.508 -0.9398)
			(end -0.508 0.9398)
			(stroke
				(width 0.1524)
				(type default)
			)
			(layer "F.SilkS")
		)
		(fp_rect
			(start -0.508 0.9398)
			(end 0.508 -0.9398)
			(stroke
				(width 0)
				(type default)
			)
			(fill no)
			(layer "F.CrtYd")
		)
		(fp_rect
			(start -0.508 0.9398)
			(end 0.508 -0.9398)
			(stroke
				(width 0)
				(type default)
			)
			(fill no)
			(layer "F.Fab")
		)
		(pad "1" smd custom
			(at 0 -0.4445 90)
			(size 0.1397 0.1397)
			(layers "F.Cu" "F.Mask" "F.Paste")
			(net "P0V9_VSNS")
			(options
				(clearance outline)
				(anchor circle)
			)
			(primitives
				(gr_poly
					(pts
						(arc
							(start -0.1778 -0.2794)
							(mid -0.249642 -0.249642)
							(end -0.2794 -0.1778)
						)
						(arc
							(start -0.2794 0.1778)
							(mid -0.249642 0.249642)
							(end -0.1778 0.2794)
						)
						(arc
							(start 0.1778 0.2794)
							(mid 0.249642 0.249642)
							(end 0.2794 0.1778)
						)
						(arc
							(start 0.2794 -0.1778)
							(mid 0.249642 -0.249642)
							(end 0.1778 -0.2794)
						)
					)
					(width 0)
					(fill yes)
				)
			)
		)
		(pad "2" smd custom
			(at 0 0.4445 90)
			(size 0.1397 0.1397)
			(layers "F.Cu" "F.Mask" "F.Paste")
			(net "P0V9_VFB")
			(options
				(clearance outline)
				(anchor circle)
			)
			(primitives
				(gr_poly
					(pts
						(arc
							(start -0.1778 -0.2794)
							(mid -0.249642 -0.249642)
							(end -0.2794 -0.1778)
						)
						(arc
							(start -0.2794 0.1778)
							(mid -0.249642 0.249642)
							(end -0.1778 0.2794)
						)
						(arc
							(start 0.1778 0.2794)
							(mid 0.249642 0.249642)
							(end 0.2794 0.1778)
						)
						(arc
							(start 0.2794 -0.1778)
							(mid 0.249642 -0.249642)
							(end 0.1778 -0.2794)
						)
					)
					(width 0)
					(fill yes)
				)
			)
		)
	)
	(footprint ""
		(layer "F.Cu")
		(at 164.496242 -96.847406 180)
		(property "Reference" "C620"
			(at 0 0 180)
			(layer "F.SilkS")
			(hide yes)
			(effects
				(font
					(size 1.27 1.27)
				)
			)
		)
		(property "Value" "SC1U25V3KX-GP"
			(at 0 -2.8194 180)
			(unlocked yes)
			(layer "F.Fab")
			(hide yes)
			(effects
				(font
					(size 1.016 1.016)
					(thickness 0.1524)
				)
			)
		)
		(property "Device Type" "C603H36"
			(at 0 -4.3434 180)
			(unlocked yes)
			(layer "F.Fab")
			(hide yes)
			(effects
				(font
					(size 1.016 1.016)
					(thickness 0.1524)
				)
			)
		)
		(duplicate_pad_numbers_are_jumpers no)
		(fp_line
			(start 0.508 0)
			(end -0.508 0)
			(stroke
				(width 0.2032)
				(type default)
			)
			(layer "F.SilkS")
		)
		(fp_rect
			(start -0.5842 1.3335)
			(end 0.5842 -1.3335)
			(stroke
				(width 0)
				(type default)
			)
			(fill no)
			(layer "F.CrtYd")
		)
		(fp_rect
			(start -0.5842 1.3335)
			(end 0.5842 -1.3335)
			(stroke
				(width 0)
				(type default)
			)
			(fill no)
			(layer "F.Fab")
		)
		(pad "1" smd custom
			(at 0 -0.762 180)
			(size 0.2159 0.2159)
			(layers "F.Cu" "F.Mask" "F.Paste")
			(net "VT235_AVDD")
			(options
				(clearance outline)
				(anchor circle)
			)
			(primitives
				(gr_poly
					(pts
						(arc
							(start -0.3302 -0.4318)
							(mid -0.402042 -0.402042)
							(end -0.4318 -0.3302)
						)
						(arc
							(start -0.4318 0.3302)
							(mid -0.402042 0.402042)
							(end -0.3302 0.4318)
						)
						(arc
							(start 0.3302 0.4318)
							(mid 0.402042 0.402042)
							(end 0.4318 0.3302)
						)
						(arc
							(start 0.4318 -0.3302)
							(mid 0.402042 -0.402042)
							(end 0.3302 -0.4318)
						)
					)
					(width 0)
					(fill yes)
				)
			)
		)
		(pad "2" smd custom
			(at 0 0.762 180)
			(size 0.2159 0.2159)
			(layers "F.Cu" "F.Mask" "F.Paste")
			(net "AGND_P0V975")
			(options
				(clearance outline)
				(anchor circle)
			)
			(primitives
				(gr_poly
					(pts
						(arc
							(start -0.3302 -0.4318)
							(mid -0.402042 -0.402042)
							(end -0.4318 -0.3302)
						)
						(arc
							(start -0.4318 0.3302)
							(mid -0.402042 0.402042)
							(end -0.3302 0.4318)
						)
						(arc
							(start 0.3302 0.4318)
							(mid 0.402042 0.402042)
							(end 0.4318 0.3302)
						)
						(arc
							(start 0.4318 -0.3302)
							(mid 0.402042 -0.402042)
							(end 0.3302 -0.4318)
						)
					)
					(width 0)
					(fill yes)
				)
			)
		)
	)
	(footprint ""
		(layer "F.Cu")
		(at 136.525 -106.2736 -90)
		(property "Reference" "C693"
			(at 0 0 270)
			(layer "F.SilkS")
			(hide yes)
			(effects
				(font
					(size 1.27 1.27)
				)
			)
		)
		(property "Value" "SCD1U16V2KX-3GP"
			(at 1.1811 -2.7051 270)
			(unlocked yes)
			(layer "F.Fab")
			(hide yes)
			(effects
				(font
					(size 1.016 1.016)
					(thickness 0.1524)
				)
			)
		)
		(property "Device Type" "C402H22"
			(at 1.1811 -4.2291 270)
			(unlocked yes)
			(layer "F.Fab")
			(hide yes)
			(effects
				(font
					(size 1.016 1.016)
					(thickness 0.1524)
				)
			)
		)
		(duplicate_pad_numbers_are_jumpers no)
		(fp_rect
			(start -0.4318 0.9525)
			(end 0.4318 -0.9525)
			(stroke
				(width 0)
				(type default)
			)
			(fill no)
			(layer "F.CrtYd")
		)
		(fp_rect
			(start -0.4318 0.9525)
			(end 0.4318 -0.9525)
			(stroke
				(width 0)
				(type default)
			)
			(fill no)
			(layer "F.Fab")
		)
		(pad "1" smd custom
			(at 0 -0.4445 270)
			(size 0.1524 0.1524)
			(layers "F.Cu" "F.Mask" "F.Paste")
			(net "P1V5_E_OUT")
			(options
				(clearance outline)
				(anchor circle)
			)
			(primitives
				(gr_poly
					(pts
						(arc
							(start 0.3048 -0.2032)
							(mid 0.275042 -0.275042)
							(end 0.2032 -0.3048)
						)
						(arc
							(start -0.2032 -0.3048)
							(mid -0.275042 -0.275042)
							(end -0.3048 -0.2032)
						)
						(arc
							(start -0.3048 0.2032)
							(mid -0.275042 0.275042)
							(end -0.2032 0.3048)
						)
						(arc
							(start 0.2032 0.3048)
							(mid 0.275042 0.275042)
							(end 0.3048 0.2032)
						)
					)
					(width 0)
					(fill yes)
				)
			)
		)
		(pad "2" smd custom
			(at 0 0.4445 270)
			(size 0.1524 0.1524)
			(layers "F.Cu" "F.Mask" "F.Paste")
			(net "GND")
			(options
				(clearance outline)
				(anchor circle)
			)
			(primitives
				(gr_poly
					(pts
						(arc
							(start 0.3048 -0.2032)
							(mid 0.275042 -0.275042)
							(end 0.2032 -0.3048)
						)
						(arc
							(start -0.2032 -0.3048)
							(mid -0.275042 -0.275042)
							(end -0.3048 -0.2032)
						)
						(arc
							(start -0.3048 0.2032)
							(mid -0.275042 0.275042)
							(end -0.2032 0.3048)
						)
						(arc
							(start 0.2032 0.3048)
							(mid 0.275042 0.275042)
							(end 0.3048 0.2032)
						)
					)
					(width 0)
					(fill yes)
				)
			)
		)
	)
	(footprint ""
		(layer "F.Cu")
		(at 185.3946 -119.2276 -90)
		(property "Reference" "C597"
			(at 0 0 270)
			(layer "F.SilkS")
			(hide yes)
			(effects
				(font
					(size 1.27 1.27)
				)
			)
		)
		(property "Value" "SC10U6D3V5KX-4GP"
			(at -0.0762 -6.1214 270)
			(unlocked yes)
			(layer "F.Fab")
			(hide yes)
			(effects
				(font
					(size 1.016 1.016)
					(thickness 0.1524)
				)
			)
		)
		(property "Device Type" "C805H58"
			(at -0.0762 -8.1534 270)
			(unlocked yes)
			(layer "F.Fab")
			(hide yes)
			(effects
				(font
					(size 1.016 1.016)
					(thickness 0.1524)
				)
			)
		)
		(duplicate_pad_numbers_are_jumpers no)
		(fp_line
			(start 0.635 0)
			(end -0.635 0)
			(stroke
				(width 0.508)
				(type default)
			)
			(layer "F.SilkS")
		)
		(fp_rect
			(start -0.9652 1.778)
			(end 0.9652 -1.778)
			(stroke
				(width 0)
				(type default)
			)
			(fill no)
			(layer "F.CrtYd")
		)
		(fp_poly
			(pts
				(xy -0.9652 -1.778) (xy 0.9652 -1.778) (xy 0.9652 1.778) (xy -0.9652 1.778)
			)
			(stroke
				(width 0)
				(type default)
			)
			(fill no)
			(layer "F.Fab")
		)
		(pad "1" smd rect
			(at 0 -0.9652 270)
			(size 1.397 1.143)
			(layers "F.Cu" "F.Mask" "F.Paste")
			(net "P1V8_C")
		)
		(pad "2" smd rect
			(at 0 0.9652 270)
			(size 1.397 1.143)
			(layers "F.Cu" "F.Mask" "F.Paste")
			(net "GND")
		)
	)
	(footprint ""
		(layer "F.Cu")
		(at 181.9529 -113.34242 90)
		(property "Reference" "R98"
			(at 0 0 90)
			(layer "F.SilkS")
			(hide yes)
			(effects
				(font
					(size 1.27 1.27)
				)
			)
		)
		(property "Value" "2K87R2F-1-GP"
			(at 0.064008 -3.993896 90)
			(unlocked yes)
			(layer "F.Fab")
			(hide yes)
			(effects
				(font
					(size 1.016 1.016)
					(thickness 0.1524)
				)
			)
		)
		(property "Device Type" "R402H16"
			(at 0.064008 -5.517896 90)
			(unlocked yes)
			(layer "F.Fab")
			(hide yes)
			(effects
				(font
					(size 1.016 1.016)
					(thickness 0.1524)
				)
			)
		)
		(duplicate_pad_numbers_are_jumpers no)
		(fp_line
			(start 0.508 -0.9398)
			(end -0.508 -0.9398)
			(stroke
				(width 0.1524)
				(type default)
			)
			(layer "F.SilkS")
		)
		(fp_line
			(start -0.508 -0.9398)
			(end -0.508 0.9398)
			(stroke
				(width 0.1524)
				(type default)
			)
			(layer "F.SilkS")
		)
		(fp_rect
			(start -0.508 0.9398)
			(end 0.508 -0.9398)
			(stroke
				(width 0)
				(type default)
			)
			(fill no)
			(layer "F.CrtYd")
		)
		(fp_rect
			(start -0.508 0.9398)
			(end 0.508 -0.9398)
			(stroke
				(width 0)
				(type default)
			)
			(fill no)
			(layer "F.Fab")
		)
		(pad "1" smd custom
			(at 0 -0.4445 90)
			(size 0.1397 0.1397)
			(layers "F.Cu" "F.Mask" "F.Paste")
			(net "P1V8_E_FB")
			(options
				(clearance outline)
				(anchor circle)
			)
			(primitives
				(gr_poly
					(pts
						(arc
							(start -0.1778 -0.2794)
							(mid -0.249642 -0.249642)
							(end -0.2794 -0.1778)
						)
						(arc
							(start -0.2794 0.1778)
							(mid -0.249642 0.249642)
							(end -0.1778 0.2794)
						)
						(arc
							(start 0.1778 0.2794)
							(mid 0.249642 0.249642)
							(end 0.2794 0.1778)
						)
						(arc
							(start 0.2794 -0.1778)
							(mid 0.249642 -0.249642)
							(end 0.1778 -0.2794)
						)
					)
					(width 0)
					(fill yes)
				)
			)
		)
		(pad "2" smd custom
			(at 0 0.4445 90)
			(size 0.1397 0.1397)
			(layers "F.Cu" "F.Mask" "F.Paste")
			(net "GND")
			(options
				(clearance outline)
				(anchor circle)
			)
			(primitives
				(gr_poly
					(pts
						(arc
							(start -0.1778 -0.2794)
							(mid -0.249642 -0.249642)
							(end -0.2794 -0.1778)
						)
						(arc
							(start -0.2794 0.1778)
							(mid -0.249642 0.249642)
							(end -0.1778 0.2794)
						)
						(arc
							(start 0.1778 0.2794)
							(mid 0.249642 0.249642)
							(end 0.2794 0.1778)
						)
						(arc
							(start 0.2794 -0.1778)
							(mid 0.249642 -0.249642)
							(end 0.1778 -0.2794)
						)
					)
					(width 0)
					(fill yes)
				)
			)
		)
	)
)
